(kicad_pcb
	(version 20260206)
	(generator "pcbnew")
	(generator_version "10.0")
	(general
		(thickness 1.6)
		(legacy_teardrops no)
	)
	(paper "A4")
	(title_block
		(title "Wiwynn_Tioga_Pass_MB.brd")
		(comment 1 "Tioga Pass / footprint 1664 of 4770 (U7C1), pads 696-813 of 1310")
	)
	(layers
		(0 "F.Cu" signal "TOP")
		(4 "In1.Cu" signal "L2GND")
		(6 "In2.Cu" signal "L3")
		(8 "In3.Cu" signal "L4GND")
		(10 "In4.Cu" signal "L5")
		(12 "In5.Cu" signal "L6GND")
		(14 "In6.Cu" signal "L7VCC")
		(16 "In7.Cu" signal "L8VCC")
		(18 "In8.Cu" signal "L9GND")
		(20 "In9.Cu" signal "L10")
		(22 "In10.Cu" signal "L11GND")
		(24 "In11.Cu" signal "L12")
		(26 "In12.Cu" signal "L13GND")
		(2 "B.Cu" signal "BOTTOM")
		(9 "F.Adhes" user "F.Adhesive")
		(11 "B.Adhes" user "B.Adhesive")
		(13 "F.Paste" user "Package Geometry/Pastemask Top")
		(15 "B.Paste" user "Package Geometry/Pastemask Bottom")
		(5 "F.SilkS" user "Ref Des/Silkscreen Top")
		(7 "B.SilkS" user "Ref Des/Silkscreen Bottom")
		(1 "F.Mask" user "Board Geometry/Soldermask Top")
		(3 "B.Mask" user "Board Geometry/Soldermask Bottom")
		(17 "Dwgs.User" user "User.Drawings")
		(19 "Cmts.User" user "User.Comments")
		(21 "Eco1.User" user "User.Eco1")
		(23 "Eco2.User" user "User.Eco2")
		(25 "Edge.Cuts" user "Board Geometry/Outline")
		(27 "Margin" user)
		(31 "F.CrtYd" user "Package Geometry/Place Bound Top")
		(29 "B.CrtYd" user "Package Geometry/Place Bound Bottom")
		(35 "F.Fab" user "Ref Des/Assembly Top")
		(33 "B.Fab" user "Ref Des/Assembly Bottom")
	)
	(footprint ""
		(layer "F.Cu")
		(at 387.985 -109.855 90)
		(property "Reference" "U7C1"
			(at 17.75333 -13.335 0)
			(unlocked yes)
			(layer "F.SilkS")
			(effects
				(font
					(size 0.7874 0.5842)
					(thickness 0.1524)
				)
				(justify left)
			)
		)
		(property "Value" ""
			(at 0 0 90)
			(layer "F.Fab")
			(effects
				(font
					(size 1.27 1.27)
				)
			)
		)
		(duplicate_pad_numbers_are_jumpers no)
		(pad "BL44" smd circle
			(at 3.43408 9.16305)
			(size 0.381 0.381)
			(layers "F.Cu" "F.Mask" "F.Paste")
			(net "SMB_SLOTX24_PCH_STBY_LVC3_SDA")
		)
		(pad "BL48" smd circle
			(at 5.15112 9.16305)
			(size 0.381 0.381)
			(layers "F.Cu" "F.Mask" "F.Paste")
			(net "FM_OC0_USB_N")
		)
		(pad "BL52" smd circle
			(at 6.86816 9.16305)
			(size 0.381 0.381)
			(layers "F.Cu" "F.Mask" "F.Paste")
			(net "USB3_P01_TXN")
		)
		(pad "BL56" smd circle
			(at 8.5852 9.16305)
			(size 0.381 0.381)
			(layers "F.Cu" "F.Mask" "F.Paste")
			(net "TP_USB3_P02_TXN")
		)
		(pad "BL59" smd circle
			(at 10.30224 9.16305)
			(size 0.381 0.381)
			(layers "F.Cu" "F.Mask" "F.Paste")
			(net "TP_USB3_P06_TXN")
		)
		(pad "BL63" smd circle
			(at 12.01928 9.16305)
			(size 0.381 0.381)
			(layers "F.Cu" "F.Mask" "F.Paste")
			(net "GND")
		)
		(pad "BL66" smd circle
			(at 13.73632 9.16305)
			(size 0.381 0.381)
			(layers "F.Cu" "F.Mask" "F.Paste")
			(net "P3E_PCH_M2_TX_DP<2>")
		)
		(pad "BL68" smd circle
			(at 14.649958 8.999982)
			(size 0.3048 0.3048)
			(layers "F.Cu" "F.Mask" "F.Paste")
			(net "GND")
		)
		(pad "BL70" smd circle
			(at 15.48003 8.999982)
			(size 0.3048 0.3048)
			(layers "F.Cu" "F.Mask" "F.Paste")
			(net "GND")
		)
		(pad "BL72" smd oval
			(at 16.310102 8.999982 180)
			(size 0.254 0.3302)
			(layers "F.Cu" "F.Mask" "F.Paste")
			(net "GND")
		)
		(pad "BM2" smd circle
			(at -15.895066 9.500108 180)
			(size 0.3048 0.3048)
			(layers "F.Cu" "F.Mask" "F.Paste")
			(net "LED_GBE_P3_1")
		)
		(pad "BM4" smd circle
			(at -15.064994 9.500108 180)
			(size 0.3048 0.3048)
			(layers "F.Cu" "F.Mask" "F.Paste")
			(net "SMB_PCH_MEZZ_LOM0_SCL")
		)
		(pad "BM9" smd circle
			(at -12.8778 9.65835)
			(size 0.381 0.381)
			(layers "F.Cu" "F.Mask" "F.Paste")
			(net "GND")
		)
		(pad "BM13" smd circle
			(at -11.16076 9.65835)
			(size 0.381 0.381)
			(layers "F.Cu" "F.Mask" "F.Paste")
			(net "GND")
		)
		(pad "BM17" smd circle
			(at -9.44372 9.65835)
			(size 0.381 0.381)
			(layers "F.Cu" "F.Mask" "F.Paste")
			(net "GND")
		)
		(pad "BM20" smd circle
			(at -7.72668 9.65835)
			(size 0.381 0.381)
			(layers "F.Cu" "F.Mask" "F.Paste")
			(net "FM_PCH_BMC_THERMTRIP_EXI_STRAP_")
		)
		(pad "BM24" smd circle
			(at -6.00964 9.65835)
			(size 0.381 0.381)
			(layers "F.Cu" "F.Mask" "F.Paste")
			(net "KR_P1_OCP_TX_DN")
		)
		(pad "BM27" smd circle
			(at -4.2926 9.65835)
			(size 0.381 0.381)
			(layers "F.Cu" "F.Mask" "F.Paste")
			(net "KR_P0_OCP_TX_DN")
		)
		(pad "BM31" smd circle
			(at -2.57556 9.65835)
			(size 0.381 0.381)
			(layers "F.Cu" "F.Mask" "F.Paste")
			(net "Net_442")
		)
		(pad "BM35" smd circle
			(at -0.85852 9.65835)
			(size 0.381 0.381)
			(layers "F.Cu" "F.Mask" "F.Paste")
			(net "Net_439")
		)
		(pad "BM38" smd circle
			(at 0.85852 9.65835)
			(size 0.381 0.381)
			(layers "F.Cu" "F.Mask" "F.Paste")
			(net "FM_BMC_ENABLE_N")
		)
		(pad "BM42" smd circle
			(at 2.57556 9.65835)
			(size 0.381 0.381)
			(layers "F.Cu" "F.Mask" "F.Paste")
			(net "FM_PCH_PLD_DATA_R")
		)
		(pad "BM46" smd circle
			(at 4.2926 9.65835)
			(size 0.381 0.381)
			(layers "F.Cu" "F.Mask" "F.Paste")
			(net "GND")
		)
		(pad "BM50" smd circle
			(at 6.00964 9.65835)
			(size 0.381 0.381)
			(layers "F.Cu" "F.Mask" "F.Paste")
			(net "GND")
		)
		(pad "BM54" smd circle
			(at 7.72668 9.65835)
			(size 0.381 0.381)
			(layers "F.Cu" "F.Mask" "F.Paste")
			(net "TP_USB3_P03_TXN")
		)
		(pad "BM58" smd circle
			(at 9.44372 9.65835)
			(size 0.381 0.381)
			(layers "F.Cu" "F.Mask" "F.Paste")
			(net "GND")
		)
		(pad "BM61" smd circle
			(at 11.16076 9.65835)
			(size 0.381 0.381)
			(layers "F.Cu" "F.Mask" "F.Paste")
			(net "TP_USB3_P06_TXP")
		)
		(pad "BM65" smd circle
			(at 12.8778 9.65835)
			(size 0.381 0.381)
			(layers "F.Cu" "F.Mask" "F.Paste")
			(net "P3E_PCH_M2_TX_DN<1>")
		)
		(pad "BM69" smd circle
			(at 15.064994 9.500108)
			(size 0.3048 0.3048)
			(layers "F.Cu" "F.Mask" "F.Paste")
			(net "GND")
		)
		(pad "BM71" smd circle
			(at 15.895066 9.500108)
			(size 0.3048 0.3048)
			(layers "F.Cu" "F.Mask" "F.Paste")
			(net "GND")
		)
		(pad "BN1" smd circle
			(at -16.310102 10.063734 90)
			(size 0.3556 0.3556)
			(layers "F.Cu" "F.Mask" "F.Paste")
			(net "GND")
		)
		(pad "BN3" smd circle
			(at -15.48003 9.99998 180)
			(size 0.3048 0.3048)
			(layers "F.Cu" "F.Mask" "F.Paste")
			(net "SMB_PCH_MEZZ_LOM0_SDA")
		)
		(pad "BN5" smd circle
			(at -14.649958 9.99998 180)
			(size 0.3048 0.3048)
			(layers "F.Cu" "F.Mask" "F.Paste")
			(net "GND")
		)
		(pad "BN7" smd circle
			(at -13.73632 10.15365)
			(size 0.381 0.381)
			(layers "F.Cu" "F.Mask" "F.Paste")
			(net "IRQ_PVDDQ_ABC_VRHOT_LVT3_N")
		)
		(pad "BN11" smd circle
			(at -12.01928 10.15365)
			(size 0.381 0.381)
			(layers "F.Cu" "F.Mask" "F.Paste")
			(net "FP_NMI_BTN_N")
		)
		(pad "BN15" smd circle
			(at -10.30224 10.15365)
			(size 0.381 0.381)
			(layers "F.Cu" "F.Mask" "F.Paste")
			(net "PU_IRQ_VRALERT_N")
		)
		(pad "BN18" smd circle
			(at -8.5852 10.15365)
			(size 0.381 0.381)
			(layers "F.Cu" "F.Mask" "F.Paste")
			(net "RST_PLTRST_N")
		)
		(pad "BN22" smd circle
			(at -6.86816 10.15365)
			(size 0.381 0.381)
			(layers "F.Cu" "F.Mask" "F.Paste")
			(net "GND")
		)
		(pad "BN26" smd circle
			(at -5.15112 10.15365)
			(size 0.381 0.381)
			(layers "F.Cu" "F.Mask" "F.Paste")
			(net "TP_10GBE_KR0_MON_DP")
		)
		(pad "BN29" smd circle
			(at -3.43408 10.15365)
			(size 0.381 0.381)
			(layers "F.Cu" "F.Mask" "F.Paste")
			(net "TP_PCH_RSVD37")
		)
		(pad "BN33" smd circle
			(at -1.71704 10.15365)
			(size 0.381 0.381)
			(layers "F.Cu" "F.Mask" "F.Paste")
			(net "TP_10GBE_KR1_MON_DP")
		)
		(pad "BN37" smd circle
			(at 0 10.15365)
			(size 0.381 0.381)
			(layers "F.Cu" "F.Mask" "F.Paste")
			(net "GND")
		)
		(pad "BN40" smd circle
			(at 1.71704 10.15365)
			(size 0.381 0.381)
			(layers "F.Cu" "F.Mask" "F.Paste")
			(net "FM_TPM_PRES_RST_N")
		)
		(pad "BN44" smd circle
			(at 3.43408 10.15365)
			(size 0.381 0.381)
			(layers "F.Cu" "F.Mask" "F.Paste")
			(net "FM_CPU0_THERMTRIP_LATCH_LVT3_N")
		)
		(pad "BN48" smd circle
			(at 5.15112 10.15365)
			(size 0.381 0.381)
			(layers "F.Cu" "F.Mask" "F.Paste")
			(net "IRQ_BMC_PCH_SCI_LPC_N")
		)
		(pad "BN52" smd circle
			(at 6.86816 10.15365)
			(size 0.381 0.381)
			(layers "F.Cu" "F.Mask" "F.Paste")
			(net "GND")
		)
		(pad "BN56" smd circle
			(at 8.5852 10.15365)
			(size 0.381 0.381)
			(layers "F.Cu" "F.Mask" "F.Paste")
			(net "TP_USB3_P03_TXP")
		)
		(pad "BN59" smd circle
			(at 10.30224 10.15365)
			(size 0.381 0.381)
			(layers "F.Cu" "F.Mask" "F.Paste")
			(net "GND")
		)
		(pad "BN63" smd circle
			(at 12.01928 10.15365)
			(size 0.381 0.381)
			(layers "F.Cu" "F.Mask" "F.Paste")
			(net "P3E_PCH_TX_0_DP")
		)
		(pad "BN66" smd circle
			(at 13.73632 10.15365)
			(size 0.381 0.381)
			(layers "F.Cu" "F.Mask" "F.Paste")
			(net "GND")
		)
		(pad "BN68" smd circle
			(at 14.649958 9.99998)
			(size 0.3048 0.3048)
			(layers "F.Cu" "F.Mask" "F.Paste")
			(net "TP_PCH_RSVD55")
		)
		(pad "BN70" smd circle
			(at 15.48003 9.99998)
			(size 0.3048 0.3048)
			(layers "F.Cu" "F.Mask" "F.Paste")
			(net "A_USB2_COMP")
		)
		(pad "BN72" smd circle
			(at 16.310102 10.063734 90)
			(size 0.3556 0.3556)
			(layers "F.Cu" "F.Mask" "F.Paste")
			(net "GND")
		)
		(pad "BP4" smd circle
			(at -15.064994 10.500106 180)
			(size 0.3048 0.3048)
			(layers "F.Cu" "F.Mask" "F.Paste")
			(net "LED_GBE_P1_0")
		)
		(pad "BP69" smd circle
			(at 15.064994 10.500106)
			(size 0.3048 0.3048)
			(layers "F.Cu" "F.Mask" "F.Paste")
			(net "GND")
		)
		(pad "BR1" smd circle
			(at -16.310102 10.876534 225)
			(size 0.4064 0.4064)
			(layers "F.Cu" "F.Mask" "F.Paste")
			(net "GND")
		)
		(pad "BR3" smd circle
			(at -15.580106 10.999978 90)
			(size 0.3556 0.3556)
			(layers "F.Cu" "F.Mask" "F.Paste")
			(net "GND")
		)
		(pad "BR6" smd circle
			(at -14.356334 10.891012 90)
			(size 0.3048 0.3048)
			(layers "F.Cu" "F.Mask" "F.Paste")
			(net "GND")
		)
		(pad "BR9" smd circle
			(at -12.8778 10.64895)
			(size 0.381 0.381)
			(layers "F.Cu" "F.Mask" "F.Paste")
			(net "FM_QAT_EN_N")
		)
		(pad "BR13" smd circle
			(at -11.16076 10.64895)
			(size 0.381 0.381)
			(layers "F.Cu" "F.Mask" "F.Paste")
			(net "IRQ_PVDDQ_KLM_VRHOT_LVT3_N")
		)
		(pad "BR17" smd circle
			(at -9.44372 10.64895)
			(size 0.381 0.381)
			(layers "F.Cu" "F.Mask" "F.Paste")
			(net "FM_USB_P0_EN_BOOT_BIOS_STRAP_N")
		)
		(pad "BR20" smd circle
			(at -7.72668 10.64895)
			(size 0.381 0.381)
			(layers "F.Cu" "F.Mask" "F.Paste")
			(net "GND")
		)
		(pad "BR24" smd circle
			(at -6.00964 10.64895)
			(size 0.381 0.381)
			(layers "F.Cu" "F.Mask" "F.Paste")
			(net "KR_P1_OCP_TX_DP")
		)
		(pad "BR27" smd circle
			(at -4.2926 10.64895)
			(size 0.381 0.381)
			(layers "F.Cu" "F.Mask" "F.Paste")
			(net "KR_P0_OCP_TX_DP")
		)
		(pad "BR31" smd circle
			(at -2.57556 10.64895)
			(size 0.381 0.381)
			(layers "F.Cu" "F.Mask" "F.Paste")
			(net "Net_441")
		)
		(pad "BR35" smd circle
			(at -0.85852 10.64895)
			(size 0.381 0.381)
			(layers "F.Cu" "F.Mask" "F.Paste")
			(net "Net_440")
		)
		(pad "BR38" smd circle
			(at 0.85852 10.64895)
			(size 0.381 0.381)
			(layers "F.Cu" "F.Mask" "F.Paste")
			(net "FM_BMC_FAULT_LED_N")
		)
		(pad "BR42" smd circle
			(at 2.57556 10.64895)
			(size 0.381 0.381)
			(layers "F.Cu" "F.Mask" "F.Paste")
			(net "IRQ_BMC_PCH_NMI_STBY_R_N")
		)
		(pad "BR46" smd circle
			(at 4.2926 10.64895)
			(size 0.381 0.381)
			(layers "F.Cu" "F.Mask" "F.Paste")
			(net "Net_476")
		)
		(pad "BR50" smd circle
			(at 6.00964 10.64895)
			(size 0.381 0.381)
			(layers "F.Cu" "F.Mask" "F.Paste")
			(net "GND")
		)
		(pad "BR54" smd circle
			(at 7.72668 10.64895)
			(size 0.381 0.381)
			(layers "F.Cu" "F.Mask" "F.Paste")
			(net "GND")
		)
		(pad "BR58" smd circle
			(at 9.44372 10.64895)
			(size 0.381 0.381)
			(layers "F.Cu" "F.Mask" "F.Paste")
			(net "GND")
		)
		(pad "BR61" smd circle
			(at 11.16076 10.64895)
			(size 0.381 0.381)
			(layers "F.Cu" "F.Mask" "F.Paste")
			(net "P3E_PCH_TX_0_DN")
		)
		(pad "BR65" smd circle
			(at 12.8778 10.64895)
			(size 0.381 0.381)
			(layers "F.Cu" "F.Mask" "F.Paste")
			(net "P3E_PCH_M2_TX_DP<1>")
		)
		(pad "BR67" smd circle
			(at 14.356334 10.891012 90)
			(size 0.3048 0.3048)
			(layers "F.Cu" "F.Mask" "F.Paste")
			(net "A_USB2_VBUS")
		)
		(pad "BR70" smd circle
			(at 15.580106 10.999978 90)
			(size 0.3556 0.3556)
			(layers "F.Cu" "F.Mask" "F.Paste")
			(net "GND")
		)
		(pad "BR72" smd circle
			(at 16.310102 10.876534 315)
			(size 0.4064 0.4064)
			(layers "F.Cu" "F.Mask" "F.Paste")
			(net "GND")
		)
		(pad "BT5" smd circle
			(at -14.85138 11.386058 90)
			(size 0.3048 0.3048)
			(layers "F.Cu" "F.Mask" "F.Paste")
			(net "SMB_PCH_MEZZ_LOM2_SCL")
		)
		(pad "BT8" smd circle
			(at -13.5001 11.234928 90)
			(size 0.3048 0.3048)
			(layers "F.Cu" "F.Mask" "F.Paste")
			(net "GND")
		)
		(pad "BT66" smd circle
			(at 13.5001 11.234928 90)
			(size 0.3048 0.3048)
			(layers "F.Cu" "F.Mask" "F.Paste")
			(net "GND")
		)
		(pad "BT69" smd circle
			(at 14.85138 11.386058 90)
			(size 0.3048 0.3048)
			(layers "F.Cu" "F.Mask" "F.Paste")
			(net "GND")
		)
		(pad "BU1" smd circle
			(at -16.310102 11.689334 180)
			(size 0.4064 0.4064)
			(layers "F.Cu" "F.Mask" "F.Paste")
			(net "GND")
		)
		(pad "BU3" smd circle
			(at -15.580106 11.78433 90)
			(size 0.3556 0.3556)
			(layers "F.Cu" "F.Mask" "F.Paste")
			(net "GND")
		)
		(pad "BU6" smd circle
			(at -13.999972 11.649964 90)
			(size 0.3048 0.3048)
			(layers "F.Cu" "F.Mask" "F.Paste")
			(net "LED_GBE_P2_1")
		)
		(pad "BU9" smd circle
			(at -12.999974 11.649964 270)
			(size 0.3048 0.3048)
			(layers "F.Cu" "F.Mask" "F.Paste")
			(net "GND")
		)
		(pad "BU11" smd circle
			(at -11.999976 11.649964 270)
			(size 0.3048 0.3048)
			(layers "F.Cu" "F.Mask" "F.Paste")
			(net "GND")
		)
		(pad "BU13" smd circle
			(at -10.999978 11.649964 270)
			(size 0.3048 0.3048)
			(layers "F.Cu" "F.Mask" "F.Paste")
			(net "GND")
		)
		(pad "BU15" smd circle
			(at -9.99998 11.649964 270)
			(size 0.3048 0.3048)
			(layers "F.Cu" "F.Mask" "F.Paste")
			(net "GND")
		)
		(pad "BU18" smd circle
			(at -8.999982 11.649964 270)
			(size 0.3048 0.3048)
			(layers "F.Cu" "F.Mask" "F.Paste")
			(net "GND")
		)
		(pad "BU20" smd circle
			(at -7.999984 11.649964 270)
			(size 0.3048 0.3048)
			(layers "F.Cu" "F.Mask" "F.Paste")
			(net "GND")
		)
		(pad "BU22" smd circle
			(at -6.999986 11.649964 270)
			(size 0.3048 0.3048)
			(layers "F.Cu" "F.Mask" "F.Paste")
			(net "GND")
		)
		(pad "BU24" smd circle
			(at -5.999988 11.649964 270)
			(size 0.3048 0.3048)
			(layers "F.Cu" "F.Mask" "F.Paste")
			(net "GND")
		)
		(pad "BU26" smd circle
			(at -4.99999 11.649964 270)
			(size 0.3048 0.3048)
			(layers "F.Cu" "F.Mask" "F.Paste")
			(net "GND")
		)
		(pad "BU28" smd circle
			(at -3.999992 11.649964 270)
			(size 0.3048 0.3048)
			(layers "F.Cu" "F.Mask" "F.Paste")
			(net "GND")
		)
		(pad "BU30" smd circle
			(at -2.999994 11.649964 270)
			(size 0.3048 0.3048)
			(layers "F.Cu" "F.Mask" "F.Paste")
			(net "GND")
		)
		(pad "BU32" smd circle
			(at -1.999996 11.649964 270)
			(size 0.3048 0.3048)
			(layers "F.Cu" "F.Mask" "F.Paste")
			(net "GND")
		)
		(pad "BU34" smd circle
			(at -0.999998 11.649964 270)
			(size 0.3048 0.3048)
			(layers "F.Cu" "F.Mask" "F.Paste")
			(net "GND")
		)
		(pad "BU37" smd circle
			(at 0 11.649964 270)
			(size 0.3048 0.3048)
			(layers "F.Cu" "F.Mask" "F.Paste")
			(net "GND")
		)
		(pad "BU39" smd circle
			(at 0.999998 11.649964 270)
			(size 0.3048 0.3048)
			(layers "F.Cu" "F.Mask" "F.Paste")
			(net "GND")
		)
		(pad "BU41" smd circle
			(at 1.999996 11.649964 270)
			(size 0.3048 0.3048)
			(layers "F.Cu" "F.Mask" "F.Paste")
			(net "GND")
		)
		(pad "BU43" smd circle
			(at 2.999994 11.649964 270)
			(size 0.3048 0.3048)
			(layers "F.Cu" "F.Mask" "F.Paste")
			(net "GND")
		)
		(pad "BU45" smd circle
			(at 3.999992 11.649964 270)
			(size 0.3048 0.3048)
			(layers "F.Cu" "F.Mask" "F.Paste")
			(net "GND")
		)
		(pad "BU48" smd circle
			(at 4.99999 11.649964 270)
			(size 0.3048 0.3048)
			(layers "F.Cu" "F.Mask" "F.Paste")
			(net "GND")
		)
		(pad "BU50" smd circle
			(at 5.999988 11.649964 270)
			(size 0.3048 0.3048)
			(layers "F.Cu" "F.Mask" "F.Paste")
			(net "GND")
		)
		(pad "BU52" smd circle
			(at 6.999986 11.649964 270)
			(size 0.3048 0.3048)
			(layers "F.Cu" "F.Mask" "F.Paste")
			(net "GND")
		)
		(pad "BU54" smd circle
			(at 7.999984 11.649964 270)
			(size 0.3048 0.3048)
			(layers "F.Cu" "F.Mask" "F.Paste")
			(net "GND")
		)
		(pad "BU57" smd circle
			(at 8.999982 11.649964 270)
			(size 0.3048 0.3048)
			(layers "F.Cu" "F.Mask" "F.Paste")
			(net "GND")
		)
		(pad "BU59" smd circle
			(at 9.99998 11.649964 270)
			(size 0.3048 0.3048)
			(layers "F.Cu" "F.Mask" "F.Paste")
			(net "GND")
		)
		(pad "BU61" smd circle
			(at 10.999978 11.649964 270)
			(size 0.3048 0.3048)
			(layers "F.Cu" "F.Mask" "F.Paste")
			(net "GND")
		)
		(pad "BU63" smd circle
			(at 11.999976 11.649964 270)
			(size 0.3048 0.3048)
			(layers "F.Cu" "F.Mask" "F.Paste")
			(net "GND")
		)
		(pad "BU65" smd circle
			(at 12.999974 11.649964 270)
			(size 0.3048 0.3048)
			(layers "F.Cu" "F.Mask" "F.Paste")
			(net "TP_USB2_P10_DP")
		)
		(pad "BU67" smd circle
			(at 13.999972 11.649964 90)
			(size 0.3048 0.3048)
			(layers "F.Cu" "F.Mask" "F.Paste")
			(net "TP_USB2_P14_DP")
		)
		(pad "BU70" smd circle
			(at 15.580106 11.78433 90)
			(size 0.3556 0.3556)
			(layers "F.Cu" "F.Mask" "F.Paste")
			(net "GND")
		)
		(pad "BU72" smd circle
			(at 16.310102 11.689334 315)
			(size 0.4064 0.4064)
			(layers "F.Cu" "F.Mask" "F.Paste")
			(net "GND")
		)
		(pad "BV8" smd circle
			(at -13.5001 12.065 270)
			(size 0.3048 0.3048)
			(layers "F.Cu" "F.Mask" "F.Paste")
			(net "SMB_PCH_MEZZ_LOM1_SDA")
		)
		(pad "BV10" smd circle
			(at -12.500102 12.065 270)
			(size 0.3048 0.3048)
			(layers "F.Cu" "F.Mask" "F.Paste")
			(net "FM_GBE0_LVC3_MOD_ABS")
		)
		(pad "BV12" smd circle
			(at -11.500104 12.065 270)
			(size 0.3048 0.3048)
			(layers "F.Cu" "F.Mask" "F.Paste")
			(net "TP_PCH_GPP_J21")
		)
		(pad "BV14" smd circle
			(at -10.500106 12.065 270)
			(size 0.3048 0.3048)
			(layers "F.Cu" "F.Mask" "F.Paste")
			(net "TP_PCH_GPP_J23")
		)
	)
)
